# SCM (Grand Teton) — schematic netlist excerpt (pin names and nets, part order shuffled) for the footprints in the layout excerpt that follows; sources: Cadence DE-HDL packaged netlist, KiCad conversion of 12092022_DA0F0TMDCD0_F0T_Management_Board_D_brd_V3_OCP.brd

PC257  Q_CAP  22UF 4V 20% X6S  pkg 0805  page 55 : A = P1V2_AUX ; B = GND
L29  Q_INDUCTOR  BLM18BB470/500MA IND  pkg SMLF  page 23 : \1\ = V_DACG ; \2\ = V_DACG_IO

(kicad_pcb
	(version 20260206)
	(generator "pcbnew")
	(generator_version "10.0")
	(general
		(thickness 1.6)
		(legacy_teardrops no)
	)
	(paper "A4")
	(title_block
		(title "12092022_DA0F0TMDCD0_F0T_Management_Board_D_brd_V3_OCP.brd")
		(comment 1 "Grand Teton / footprints 428-429 of 1440")
	)
	(layers
		(0 "F.Cu" signal "TOP")
		(4 "In1.Cu" signal "GND")
		(6 "In2.Cu" signal "IN1")
		(8 "In3.Cu" signal "GND1")
		(10 "In4.Cu" signal "IN2")
		(12 "In5.Cu" signal "VCC")
		(14 "In6.Cu" signal "VCC1")
		(16 "In7.Cu" signal "IN3")
		(18 "In8.Cu" signal "GND2")
		(20 "In9.Cu" signal "IN4")
		(22 "In10.Cu" signal "GND3")
		(2 "B.Cu" signal "BOTTOM")
		(9 "F.Adhes" user "F.Adhesive")
		(11 "B.Adhes" user "B.Adhesive")
		(13 "F.Paste" user "Package Geometry/Pastemask Top")
		(15 "B.Paste" user "Package Geometry/Pastemask Bottom")
		(5 "F.SilkS" user "Ref Des/Silkscreen Top")
		(7 "B.SilkS" user "Ref Des/Silkscreen Bottom")
		(1 "F.Mask" user "Board Geometry/Soldermask Top")
		(3 "B.Mask" user "Board Geometry/Soldermask Bottom")
		(17 "Dwgs.User" user "User.Drawings")
		(19 "Cmts.User" user "User.Comments")
		(21 "Eco1.User" user "User.Eco1")
		(23 "Eco2.User" user "User.Eco2")
		(25 "Edge.Cuts" user "Board Geometry/Outline")
		(27 "Margin" user)
		(31 "F.CrtYd" user "Package Geometry/Place Bound Top")
		(29 "B.CrtYd" user "Package Geometry/Place Bound Bottom")
		(35 "F.Fab" user "Ref Des/Assembly Top")
		(33 "B.Fab" user "Ref Des/Assembly Bottom")
	)
	(footprint ""
		(layer "F.Cu")
		(at 29.2608 -30.099)
		(property "Reference" "L29"
			(at 0 0 0)
			(layer "F.SilkS")
			(hide yes)
			(effects
				(font
					(size 1.27 1.27)
				)
			)
		)
		(property "Value" ""
			(at 0 0 0)
			(layer "F.Fab")
			(effects
				(font
					(size 1.27 1.27)
				)
			)
		)
		(duplicate_pad_numbers_are_jumpers no)
		(fp_line
			(start -1.27 -0.5842)
			(end 1.27 -0.5842)
			(stroke
				(width 0.1524)
				(type default)
			)
			(layer "F.SilkS")
		)
		(fp_line
			(start -1.27 -0.5588)
			(end -1.27 -0.5842)
			(stroke
				(width 0.1524)
				(type default)
			)
			(layer "F.SilkS")
		)
		(fp_line
			(start -1.27 0.5842)
			(end -1.27 -0.5842)
			(stroke
				(width 0.1524)
				(type default)
			)
			(layer "F.SilkS")
		)
		(fp_line
			(start -0.127 0.5842)
			(end -0.127 -0.5842)
			(stroke
				(width 0.1524)
				(type default)
			)
			(layer "F.SilkS")
		)
		(fp_line
			(start 0.127 0.5842)
			(end 0.127 -0.5842)
			(stroke
				(width 0.1524)
				(type default)
			)
			(layer "F.SilkS")
		)
		(fp_line
			(start 1.27 0.5842)
			(end -1.27 0.5842)
			(stroke
				(width 0.1524)
				(type default)
			)
			(layer "F.SilkS")
		)
		(fp_line
			(start 1.27 0.5842)
			(end 1.27 -0.5842)
			(stroke
				(width 0.1524)
				(type default)
			)
			(layer "F.SilkS")
		)
		(fp_line
			(start -1.194308 -0.406654)
			(end -0.9144 -0.406654)
			(stroke
				(width 0.1)
				(type default)
			)
			(layer "F.Fab")
		)
		(fp_line
			(start -1.194308 0.406654)
			(end -1.194308 -0.406654)
			(stroke
				(width 0.1)
				(type default)
			)
			(layer "F.Fab")
		)
		(fp_line
			(start -0.9144 -0.508)
			(end 0.9144 -0.508)
			(stroke
				(width 0.1)
				(type default)
			)
			(layer "F.Fab")
		)
		(fp_line
			(start -0.9144 -0.406654)
			(end -0.9144 -0.508)
			(stroke
				(width 0.1)
				(type default)
			)
			(layer "F.Fab")
		)
		(fp_line
			(start -0.9144 0.406654)
			(end -1.194308 0.406654)
			(stroke
				(width 0.1)
				(type default)
			)
			(layer "F.Fab")
		)
		(fp_line
			(start -0.9144 0.508)
			(end -0.9144 0.406654)
			(stroke
				(width 0.1)
				(type default)
			)
			(layer "F.Fab")
		)
		(fp_line
			(start 0.9144 -0.508)
			(end 0.9144 -0.406654)
			(stroke
				(width 0.1)
				(type default)
			)
			(layer "F.Fab")
		)
		(fp_line
			(start 0.9144 -0.406654)
			(end 1.1938 -0.406654)
			(stroke
				(width 0.1)
				(type default)
			)
			(layer "F.Fab")
		)
		(fp_line
			(start 0.9144 0.4064)
			(end 0.9144 0.508)
			(stroke
				(width 0.1)
				(type default)
			)
			(layer "F.Fab")
		)
		(fp_line
			(start 0.9144 0.508)
			(end -0.9144 0.508)
			(stroke
				(width 0.1)
				(type default)
			)
			(layer "F.Fab")
		)
		(fp_line
			(start 1.1938 -0.406654)
			(end 1.1938 0.4064)
			(stroke
				(width 0.1)
				(type default)
			)
			(layer "F.Fab")
		)
		(fp_line
			(start 1.1938 0.4064)
			(end 0.9144 0.4064)
			(stroke
				(width 0.1)
				(type default)
			)
			(layer "F.Fab")
		)
		(pad "1" smd rect
			(at -0.7366 0 270)
			(size 0.7112 0.8128)
			(layers "F.Cu" "F.Mask" "F.Paste")
			(net "V_DACG")
		)
		(pad "2" smd rect
			(at 0.7366 0 270)
			(size 0.7112 0.8128)
			(layers "F.Cu" "F.Mask" "F.Paste")
			(net "V_DACG_IO")
		)
	)
	(footprint ""
		(layer "F.Cu")
		(at 81.818988 -59.05373 -90)
		(property "Reference" "PC257"
			(at 0 0 270)
			(layer "F.SilkS")
			(hide yes)
			(effects
				(font
					(size 1.27 1.27)
				)
			)
		)
		(property "Value" ""
			(at 0 0 270)
			(layer "F.Fab")
			(effects
				(font
					(size 1.27 1.27)
				)
			)
		)
		(duplicate_pad_numbers_are_jumpers no)
		(fp_line
			(start -1.651 0.8382)
			(end -1.651 -0.8382)
			(stroke
				(width 0.1524)
				(type default)
			)
			(layer "F.SilkS")
		)
		(fp_line
			(start 0 0.8382)
			(end 0 -0.8382)
			(stroke
				(width 0.1524)
				(type default)
			)
			(layer "F.SilkS")
		)
		(fp_line
			(start 1.651 0.8382)
			(end -1.651 0.8382)
			(stroke
				(width 0.1524)
				(type default)
			)
			(layer "F.SilkS")
		)
		(fp_line
			(start -1.651 -0.8382)
			(end 1.651 -0.8382)
			(stroke
				(width 0.1524)
				(type default)
			)
			(layer "F.SilkS")
		)
		(fp_line
			(start 1.651 -0.8382)
			(end 1.651 0.8382)
			(stroke
				(width 0.1524)
				(type default)
			)
			(layer "F.SilkS")
		)
		(fp_line
			(start -1.55956 0.7366)
			(end -1.524 0.7366)
			(stroke
				(width 0.1)
				(type default)
			)
			(layer "F.Fab")
		)
		(fp_line
			(start -1.524 0.7366)
			(end 1.524 0.7366)
			(stroke
				(width 0.1)
				(type default)
			)
			(layer "F.Fab")
		)
		(fp_line
			(start 1.524 0.7366)
			(end 1.55956 0.7366)
			(stroke
				(width 0.1)
				(type default)
			)
			(layer "F.Fab")
		)
		(fp_line
			(start 1.55956 0.7366)
			(end 1.55956 -0.7366)
			(stroke
				(width 0.1)
				(type default)
			)
			(layer "F.Fab")
		)
		(fp_line
			(start -1.55956 -0.7366)
			(end -1.55956 0.7366)
			(stroke
				(width 0.1)
				(type default)
			)
			(layer "F.Fab")
		)
		(fp_line
			(start -1.524 -0.7366)
			(end -1.55956 -0.7366)
			(stroke
				(width 0.1)
				(type default)
			)
			(layer "F.Fab")
		)
		(fp_line
			(start 1.524 -0.7366)
			(end -1.524 -0.7366)
			(stroke
				(width 0.1)
				(type default)
			)
			(layer "F.Fab")
		)
		(fp_line
			(start 1.55956 -0.7366)
			(end 1.524 -0.7366)
			(stroke
				(width 0.1)
				(type default)
			)
			(layer "F.Fab")
		)
		(pad "1" smd rect
			(at -0.94996 0 90)
			(size 1.1176 1.3716)
			(layers "F.Cu" "F.Mask" "F.Paste")
			(net "P1V2_AUX")
		)
		(pad "2" smd rect
			(at 0.94996 0 90)
			(size 1.1176 1.3716)
			(layers "F.Cu" "F.Mask" "F.Paste")
			(net "GND")
		)
	)
)
